(kicad_pcb
	(version 20260206)
	(generator "pcbnew")
	(generator_version "10.0")
	(general
		(thickness 1.6)
		(legacy_teardrops no)
	)
	(paper "A4")
	(title_block
		(title "04192023_DAF0TMB3IC0_F0TG_MB_C_brd_V02_OCP.brd")
		(comment 1 "Grand Teton / footprints 463-469 of 8354")
	)
	(layers
		(0 "F.Cu" signal "TOP")
		(4 "In1.Cu" signal "GND")
		(6 "In2.Cu" signal "IN1")
		(8 "In3.Cu" signal "GND1")
		(10 "In4.Cu" signal "IN2")
		(12 "In5.Cu" signal "GND2")
		(14 "In6.Cu" signal "IN3")
		(16 "In7.Cu" signal "GND3")
		(18 "In8.Cu" signal "VCC")
		(20 "In9.Cu" signal "VCC1")
		(22 "In10.Cu" signal "GND4")
		(24 "In11.Cu" signal "IN4")
		(26 "In12.Cu" signal "GND5")
		(28 "In13.Cu" signal "IN5")
		(30 "In14.Cu" signal "GND6")
		(32 "In15.Cu" signal "IN6")
		(34 "In16.Cu" signal "GND7")
		(2 "B.Cu" signal "BOTTOM")
		(9 "F.Adhes" user "F.Adhesive")
		(11 "B.Adhes" user "B.Adhesive")
		(13 "F.Paste" user "Package Geometry/Pastemask Top")
		(15 "B.Paste" user "Package Geometry/Pastemask Bottom")
		(5 "F.SilkS" user "Ref Des/Silkscreen Top")
		(7 "B.SilkS" user "Ref Des/Silkscreen Bottom")
		(1 "F.Mask" user "Board Geometry/Soldermask Top")
		(3 "B.Mask" user "Board Geometry/Soldermask Bottom")
		(17 "Dwgs.User" user "User.Drawings")
		(19 "Cmts.User" user "User.Comments")
		(21 "Eco1.User" user "User.Eco1")
		(23 "Eco2.User" user "User.Eco2")
		(25 "Edge.Cuts" user "Board Geometry/Outline")
		(27 "Margin" user)
		(31 "F.CrtYd" user "Package Geometry/Place Bound Top")
		(29 "B.CrtYd" user "Package Geometry/Place Bound Bottom")
		(35 "F.Fab" user "Ref Des/Assembly Top")
		(33 "B.Fab" user "Ref Des/Assembly Bottom")
	)
	(footprint ""
		(layer "F.Cu")
		(at 66.726054 -337.665314 90)
		(property "Reference" "PC400"
			(at 0 0 90)
			(layer "F.SilkS")
			(hide yes)
			(effects
				(font
					(size 1.27 1.27)
				)
			)
		)
		(property "Value" ""
			(at 0 0 90)
			(layer "F.Fab")
			(effects
				(font
					(size 1.27 1.27)
				)
			)
		)
		(duplicate_pad_numbers_are_jumpers no)
		(fp_line
			(start 0.7874 -0.4064)
			(end 0.7874 0.4064)
			(stroke
				(width 0.1524)
				(type default)
			)
			(layer "F.SilkS")
		)
		(fp_line
			(start -0.7874 -0.4064)
			(end 0.7874 -0.4064)
			(stroke
				(width 0.1524)
				(type default)
			)
			(layer "F.SilkS")
		)
		(fp_line
			(start 0.7874 0.4064)
			(end 0.408686 0.4064)
			(stroke
				(width 0.1524)
				(type default)
			)
			(layer "F.SilkS")
		)
		(fp_line
			(start -0.226314 0.4064)
			(end -0.7874 0.4064)
			(stroke
				(width 0.1524)
				(type default)
			)
			(layer "F.SilkS")
		)
		(fp_line
			(start -0.7874 0.4064)
			(end -0.7874 -0.4064)
			(stroke
				(width 0.1524)
				(type default)
			)
			(layer "F.SilkS")
		)
		(fp_line
			(start -0.12065 -0.305054)
			(end -0.12065 -0.2794)
			(stroke
				(width 0.1)
				(type default)
			)
			(layer "F.Fab")
		)
		(fp_line
			(start -0.67945 -0.305054)
			(end -0.12065 -0.305054)
			(stroke
				(width 0.1)
				(type default)
			)
			(layer "F.Fab")
		)
		(fp_line
			(start 0.67945 -0.3048)
			(end 0.67945 0.3048)
			(stroke
				(width 0.1)
				(type default)
			)
			(layer "F.Fab")
		)
		(fp_line
			(start 0.12065 -0.3048)
			(end 0.67945 -0.3048)
			(stroke
				(width 0.1)
				(type default)
			)
			(layer "F.Fab")
		)
		(fp_line
			(start 0.12065 -0.2794)
			(end 0.12065 -0.3048)
			(stroke
				(width 0.1)
				(type default)
			)
			(layer "F.Fab")
		)
		(fp_line
			(start -0.12065 -0.2794)
			(end 0.12065 -0.2794)
			(stroke
				(width 0.1)
				(type default)
			)
			(layer "F.Fab")
		)
		(fp_line
			(start 0.120396 0.2794)
			(end -0.12065 0.2794)
			(stroke
				(width 0.1)
				(type default)
			)
			(layer "F.Fab")
		)
		(fp_line
			(start -0.12065 0.2794)
			(end -0.12065 0.3048)
			(stroke
				(width 0.1)
				(type default)
			)
			(layer "F.Fab")
		)
		(fp_line
			(start 0.67945 0.3048)
			(end 0.120396 0.3048)
			(stroke
				(width 0.1)
				(type default)
			)
			(layer "F.Fab")
		)
		(fp_line
			(start 0.120396 0.3048)
			(end 0.120396 0.2794)
			(stroke
				(width 0.1)
				(type default)
			)
			(layer "F.Fab")
		)
		(fp_line
			(start -0.12065 0.3048)
			(end -0.67945 0.3048)
			(stroke
				(width 0.1)
				(type default)
			)
			(layer "F.Fab")
		)
		(fp_line
			(start -0.67945 0.3048)
			(end -0.67945 -0.305054)
			(stroke
				(width 0.1)
				(type default)
			)
			(layer "F.Fab")
		)
		(pad "1" smd circle
			(at -0.40005 0 90)
			(size 0 0)
			(layers "F.Cu" "F.Mask" "F.Paste")
			(net "PVDDCR_CPU1_P1_VCC3")
		)
		(pad "2" smd circle
			(at 0.40005 0 90)
			(size 0 0)
			(layers "F.Cu" "F.Mask" "F.Paste")
			(net "GND")
		)
	)
	(footprint ""
		(layer "F.Cu")
		(at 297.315128 -146.202908 180)
		(property "Reference" "R1330"
			(at 0 0 180)
			(layer "F.SilkS")
			(hide yes)
			(effects
				(font
					(size 1.27 1.27)
				)
			)
		)
		(property "Value" ""
			(at 0 0 180)
			(layer "F.Fab")
			(effects
				(font
					(size 1.27 1.27)
				)
			)
		)
		(duplicate_pad_numbers_are_jumpers no)
		(fp_line
			(start 0.7874 0.4064)
			(end -0.7874 0.4064)
			(stroke
				(width 0.1524)
				(type default)
			)
			(layer "F.SilkS")
		)
		(fp_line
			(start 0.7874 -0.4064)
			(end 0.7874 0.4064)
			(stroke
				(width 0.1524)
				(type default)
			)
			(layer "F.SilkS")
		)
		(fp_line
			(start -0.7874 0.4064)
			(end -0.7874 -0.4064)
			(stroke
				(width 0.1524)
				(type default)
			)
			(layer "F.SilkS")
		)
		(fp_line
			(start -0.7874 -0.4064)
			(end 0.7874 -0.4064)
			(stroke
				(width 0.1524)
				(type default)
			)
			(layer "F.SilkS")
		)
		(fp_line
			(start 0.67945 0.3048)
			(end 0.120396 0.3048)
			(stroke
				(width 0.1)
				(type default)
			)
			(layer "F.Fab")
		)
		(fp_line
			(start 0.67945 -0.3048)
			(end 0.67945 0.3048)
			(stroke
				(width 0.1)
				(type default)
			)
			(layer "F.Fab")
		)
		(fp_line
			(start 0.12065 -0.2794)
			(end 0.12065 -0.3048)
			(stroke
				(width 0.1)
				(type default)
			)
			(layer "F.Fab")
		)
		(fp_line
			(start 0.12065 -0.3048)
			(end 0.67945 -0.3048)
			(stroke
				(width 0.1)
				(type default)
			)
			(layer "F.Fab")
		)
		(fp_line
			(start 0.120396 0.3048)
			(end 0.120396 0.2794)
			(stroke
				(width 0.1)
				(type default)
			)
			(layer "F.Fab")
		)
		(fp_line
			(start 0.120396 0.2794)
			(end -0.12065 0.2794)
			(stroke
				(width 0.1)
				(type default)
			)
			(layer "F.Fab")
		)
		(fp_line
			(start -0.12065 0.3048)
			(end -0.67945 0.3048)
			(stroke
				(width 0.1)
				(type default)
			)
			(layer "F.Fab")
		)
		(fp_line
			(start -0.12065 0.2794)
			(end -0.12065 0.3048)
			(stroke
				(width 0.1)
				(type default)
			)
			(layer "F.Fab")
		)
		(fp_line
			(start -0.12065 -0.2794)
			(end 0.12065 -0.2794)
			(stroke
				(width 0.1)
				(type default)
			)
			(layer "F.Fab")
		)
		(fp_line
			(start -0.12065 -0.305054)
			(end -0.12065 -0.2794)
			(stroke
				(width 0.1)
				(type default)
			)
			(layer "F.Fab")
		)
		(fp_line
			(start -0.67945 0.3048)
			(end -0.67945 -0.305054)
			(stroke
				(width 0.1)
				(type default)
			)
			(layer "F.Fab")
		)
		(fp_line
			(start -0.67945 -0.305054)
			(end -0.12065 -0.305054)
			(stroke
				(width 0.1)
				(type default)
			)
			(layer "F.Fab")
		)
		(pad "1" smd rect
			(at -0.40005 0)
			(size 0.4572 0.508)
			(layers "F.Cu" "F.Mask" "F.Paste")
			(net "I3C_SPD_DDRAF_CPU0_BYPASS_SCL")
		)
		(pad "2" smd rect
			(at 0.40005 0)
			(size 0.4572 0.508)
			(layers "F.Cu" "F.Mask" "F.Paste")
			(net "I3C_SPD_DDRAF_CPU0_SCL")
		)
	)
	(footprint ""
		(layer "F.Cu")
		(at 435.181248 -35.489388 90)
		(property "Reference" "R3870"
			(at 0 0 90)
			(layer "F.SilkS")
			(hide yes)
			(effects
				(font
					(size 1.27 1.27)
				)
			)
		)
		(property "Value" ""
			(at 0 0 90)
			(layer "F.Fab")
			(effects
				(font
					(size 1.27 1.27)
				)
			)
		)
		(duplicate_pad_numbers_are_jumpers no)
		(fp_line
			(start 0.7874 -0.4064)
			(end 0.7874 0.4064)
			(stroke
				(width 0.1524)
				(type default)
			)
			(layer "F.SilkS")
		)
		(fp_line
			(start -0.7874 -0.4064)
			(end 0.7874 -0.4064)
			(stroke
				(width 0.1524)
				(type default)
			)
			(layer "F.SilkS")
		)
		(fp_line
			(start 0.7874 0.4064)
			(end -0.7874 0.4064)
			(stroke
				(width 0.1524)
				(type default)
			)
			(layer "F.SilkS")
		)
		(fp_line
			(start -0.7874 0.4064)
			(end -0.7874 -0.4064)
			(stroke
				(width 0.1524)
				(type default)
			)
			(layer "F.SilkS")
		)
		(fp_line
			(start -0.12065 -0.305054)
			(end -0.12065 -0.2794)
			(stroke
				(width 0.1)
				(type default)
			)
			(layer "F.Fab")
		)
		(fp_line
			(start -0.67945 -0.305054)
			(end -0.12065 -0.305054)
			(stroke
				(width 0.1)
				(type default)
			)
			(layer "F.Fab")
		)
		(fp_line
			(start 0.67945 -0.3048)
			(end 0.67945 0.3048)
			(stroke
				(width 0.1)
				(type default)
			)
			(layer "F.Fab")
		)
		(fp_line
			(start 0.12065 -0.3048)
			(end 0.67945 -0.3048)
			(stroke
				(width 0.1)
				(type default)
			)
			(layer "F.Fab")
		)
		(fp_line
			(start 0.12065 -0.2794)
			(end 0.12065 -0.3048)
			(stroke
				(width 0.1)
				(type default)
			)
			(layer "F.Fab")
		)
		(fp_line
			(start -0.12065 -0.2794)
			(end 0.12065 -0.2794)
			(stroke
				(width 0.1)
				(type default)
			)
			(layer "F.Fab")
		)
		(fp_line
			(start 0.120396 0.2794)
			(end -0.12065 0.2794)
			(stroke
				(width 0.1)
				(type default)
			)
			(layer "F.Fab")
		)
		(fp_line
			(start -0.12065 0.2794)
			(end -0.12065 0.3048)
			(stroke
				(width 0.1)
				(type default)
			)
			(layer "F.Fab")
		)
		(fp_line
			(start 0.67945 0.3048)
			(end 0.120396 0.3048)
			(stroke
				(width 0.1)
				(type default)
			)
			(layer "F.Fab")
		)
		(fp_line
			(start 0.120396 0.3048)
			(end 0.120396 0.2794)
			(stroke
				(width 0.1)
				(type default)
			)
			(layer "F.Fab")
		)
		(fp_line
			(start -0.12065 0.3048)
			(end -0.67945 0.3048)
			(stroke
				(width 0.1)
				(type default)
			)
			(layer "F.Fab")
		)
		(fp_line
			(start -0.67945 0.3048)
			(end -0.67945 -0.305054)
			(stroke
				(width 0.1)
				(type default)
			)
			(layer "F.Fab")
		)
		(pad "1" smd circle
			(at -0.40005 0 90)
			(size 0 0)
			(layers "F.Cu" "F.Mask" "F.Paste")
			(net "P12V_OCP_SENSE_1")
		)
		(pad "2" smd circle
			(at 0.40005 0 90)
			(size 0 0)
			(layers "F.Cu" "F.Mask" "F.Paste")
			(net "P12V_OCP_SFF_ISENSE_MAM_TIC")
		)
	)
	(footprint ""
		(layer "F.Cu")
		(at 53.895244 -408.517344 -90)
		(property "Reference" "C6634"
			(at 0 0 270)
			(layer "F.SilkS")
			(hide yes)
			(effects
				(font
					(size 1.27 1.27)
				)
			)
		)
		(property "Value" ""
			(at 0 0 270)
			(layer "F.Fab")
			(effects
				(font
					(size 1.27 1.27)
				)
			)
		)
		(duplicate_pad_numbers_are_jumpers no)
		(fp_line
			(start -0.299974 0.150114)
			(end -0.299974 -0.150114)
			(stroke
				(width 0.1)
				(type default)
			)
			(layer "F.Fab")
		)
		(fp_line
			(start 0.299974 0.150114)
			(end -0.299974 0.150114)
			(stroke
				(width 0.1)
				(type default)
			)
			(layer "F.Fab")
		)
		(fp_line
			(start -0.299974 -0.150114)
			(end 0.299974 -0.150114)
			(stroke
				(width 0.1)
				(type default)
			)
			(layer "F.Fab")
		)
		(fp_line
			(start 0.299974 -0.150114)
			(end 0.299974 0.150114)
			(stroke
				(width 0.1)
				(type default)
			)
			(layer "F.Fab")
		)
		(pad "1" smd rect
			(at -0.2667 0 270)
			(size 0.3048 0.381)
			(layers "F.Cu" "F.Mask" "F.Paste")
			(net "P5E_CPU1_P0_TX_BUF_C_DN<2>")
		)
		(pad "2" smd rect
			(at 0.2667 0 270)
			(size 0.3048 0.381)
			(layers "F.Cu" "F.Mask" "F.Paste")
			(net "P5E_CPU1_P0_TX_BUF_DN<2>")
		)
	)
	(footprint ""
		(layer "F.Cu")
		(at 300.62297 -407.79446)
		(property "Reference" "R961"
			(at 0 0 0)
			(layer "F.SilkS")
			(hide yes)
			(effects
				(font
					(size 1.27 1.27)
				)
			)
		)
		(property "Value" ""
			(at 0 0 0)
			(layer "F.Fab")
			(effects
				(font
					(size 1.27 1.27)
				)
			)
		)
		(duplicate_pad_numbers_are_jumpers no)
		(fp_line
			(start -1.2954 -0.5842)
			(end 1.2954 -0.5842)
			(stroke
				(width 0.1524)
				(type default)
			)
			(layer "F.SilkS")
		)
		(fp_line
			(start -1.2954 0.5842)
			(end -1.2954 -0.5842)
			(stroke
				(width 0.1524)
				(type default)
			)
			(layer "F.SilkS")
		)
		(fp_line
			(start 1.2954 -0.5842)
			(end 1.2954 0.5842)
			(stroke
				(width 0.1524)
				(type default)
			)
			(layer "F.SilkS")
		)
		(fp_line
			(start 1.2954 0.5842)
			(end -1.2954 0.5842)
			(stroke
				(width 0.1524)
				(type default)
			)
			(layer "F.SilkS")
		)
		(fp_line
			(start -1.1938 -0.406654)
			(end -0.8636 -0.406654)
			(stroke
				(width 0.1)
				(type default)
			)
			(layer "F.Fab")
		)
		(fp_line
			(start -1.1938 0.4064)
			(end -1.1938 -0.406654)
			(stroke
				(width 0.1)
				(type default)
			)
			(layer "F.Fab")
		)
		(fp_line
			(start -0.8636 -0.4572)
			(end 0.8636 -0.4572)
			(stroke
				(width 0.1)
				(type default)
			)
			(layer "F.Fab")
		)
		(fp_line
			(start -0.8636 -0.406654)
			(end -0.8636 -0.4572)
			(stroke
				(width 0.1)
				(type default)
			)
			(layer "F.Fab")
		)
		(fp_line
			(start -0.8636 0.4064)
			(end -1.1938 0.4064)
			(stroke
				(width 0.1)
				(type default)
			)
			(layer "F.Fab")
		)
		(fp_line
			(start -0.8636 0.4318)
			(end -0.8636 0.4064)
			(stroke
				(width 0.1)
				(type default)
			)
			(layer "F.Fab")
		)
		(fp_line
			(start -0.8636 0.4572)
			(end -0.8636 0.4318)
			(stroke
				(width 0.1)
				(type default)
			)
			(layer "F.Fab")
		)
		(fp_line
			(start 0.8636 -0.4572)
			(end 0.8636 -0.406654)
			(stroke
				(width 0.1)
				(type default)
			)
			(layer "F.Fab")
		)
		(fp_line
			(start 0.8636 -0.406654)
			(end 1.1938 -0.406654)
			(stroke
				(width 0.1)
				(type default)
			)
			(layer "F.Fab")
		)
		(fp_line
			(start 0.8636 0.4064)
			(end 0.8636 0.4572)
			(stroke
				(width 0.1)
				(type default)
			)
			(layer "F.Fab")
		)
		(fp_line
			(start 0.8636 0.4572)
			(end -0.8636 0.4572)
			(stroke
				(width 0.1)
				(type default)
			)
			(layer "F.Fab")
		)
		(fp_line
			(start 1.1938 -0.406654)
			(end 1.1938 0.4064)
			(stroke
				(width 0.1)
				(type default)
			)
			(layer "F.Fab")
		)
		(fp_line
			(start 1.1938 0.4064)
			(end 0.8636 0.4064)
			(stroke
				(width 0.1)
				(type default)
			)
			(layer "F.Fab")
		)
		(pad "1" smd rect
			(at -0.7366 0 270)
			(size 0.7112 0.8128)
			(layers "F.Cu" "F.Mask" "F.Paste")
			(net "P0V9_CPU0_RT_2D")
		)
		(pad "2" smd rect
			(at 0.7366 0 270)
			(size 0.7112 0.8128)
			(layers "F.Cu" "F.Mask" "F.Paste")
			(net "P0V9_CPU0_RT0_2A_2D")
		)
	)
	(footprint ""
		(layer "F.Cu")
		(at 308.412896 -378.95403 -90)
		(property "Reference" "C920"
			(at 0 0 270)
			(layer "F.SilkS")
			(hide yes)
			(effects
				(font
					(size 1.27 1.27)
				)
			)
		)
		(property "Value" ""
			(at 0 0 270)
			(layer "F.Fab")
			(effects
				(font
					(size 1.27 1.27)
				)
			)
		)
		(duplicate_pad_numbers_are_jumpers no)
		(fp_line
			(start -0.299974 0.150114)
			(end -0.299974 -0.150114)
			(stroke
				(width 0.1)
				(type default)
			)
			(layer "F.Fab")
		)
		(fp_line
			(start 0.299974 0.150114)
			(end -0.299974 0.150114)
			(stroke
				(width 0.1)
				(type default)
			)
			(layer "F.Fab")
		)
		(fp_line
			(start -0.299974 -0.150114)
			(end 0.299974 -0.150114)
			(stroke
				(width 0.1)
				(type default)
			)
			(layer "F.Fab")
		)
		(fp_line
			(start 0.299974 -0.150114)
			(end 0.299974 0.150114)
			(stroke
				(width 0.1)
				(type default)
			)
			(layer "F.Fab")
		)
		(pad "1" smd rect
			(at -0.2667 0 270)
			(size 0.3048 0.381)
			(layers "F.Cu" "F.Mask" "F.Paste")
			(net "P5E_CPU0_P0_TX_C_DN<6>")
		)
		(pad "2" smd rect
			(at 0.2667 0 270)
			(size 0.3048 0.381)
			(layers "F.Cu" "F.Mask" "F.Paste")
			(net "P5E_CPU0_P0_TX_DN<6>")
		)
	)
	(footprint ""
		(layer "F.Cu")
		(at 105.960164 -257.455416)
		(property "Reference" "C2270"
			(at 0 0 0)
			(layer "F.SilkS")
			(hide yes)
			(effects
				(font
					(size 1.27 1.27)
				)
			)
		)
		(property "Value" ""
			(at 0 0 0)
			(layer "F.Fab")
			(effects
				(font
					(size 1.27 1.27)
				)
			)
		)
		(duplicate_pad_numbers_are_jumpers no)
		(fp_line
			(start -0.7874 -0.4064)
			(end 0.7874 -0.4064)
			(stroke
				(width 0.1524)
				(type default)
			)
			(layer "F.SilkS")
		)
		(fp_line
			(start -0.7874 0.4064)
			(end -0.7874 -0.4064)
			(stroke
				(width 0.1524)
				(type default)
			)
			(layer "F.SilkS")
		)
		(fp_line
			(start 0.7874 -0.4064)
			(end 0.7874 0.4064)
			(stroke
				(width 0.1524)
				(type default)
			)
			(layer "F.SilkS")
		)
		(fp_line
			(start 0.7874 0.4064)
			(end -0.7874 0.4064)
			(stroke
				(width 0.1524)
				(type default)
			)
			(layer "F.SilkS")
		)
		(fp_line
			(start -0.67945 -0.305054)
			(end -0.12065 -0.305054)
			(stroke
				(width 0.1)
				(type default)
			)
			(layer "F.Fab")
		)
		(fp_line
			(start -0.67945 0.3048)
			(end -0.67945 -0.305054)
			(stroke
				(width 0.1)
				(type default)
			)
			(layer "F.Fab")
		)
		(fp_line
			(start -0.12065 -0.305054)
			(end -0.12065 -0.2794)
			(stroke
				(width 0.1)
				(type default)
			)
			(layer "F.Fab")
		)
		(fp_line
			(start -0.12065 -0.2794)
			(end 0.12065 -0.2794)
			(stroke
				(width 0.1)
				(type default)
			)
			(layer "F.Fab")
		)
		(fp_line
			(start -0.12065 0.2794)
			(end -0.12065 0.3048)
			(stroke
				(width 0.1)
				(type default)
			)
			(layer "F.Fab")
		)
		(fp_line
			(start -0.12065 0.3048)
			(end -0.67945 0.3048)
			(stroke
				(width 0.1)
				(type default)
			)
			(layer "F.Fab")
		)
		(fp_line
			(start 0.120396 0.2794)
			(end -0.12065 0.2794)
			(stroke
				(width 0.1)
				(type default)
			)
			(layer "F.Fab")
		)
		(fp_line
			(start 0.120396 0.3048)
			(end 0.120396 0.2794)
			(stroke
				(width 0.1)
				(type default)
			)
			(layer "F.Fab")
		)
		(fp_line
			(start 0.12065 -0.3048)
			(end 0.67945 -0.3048)
			(stroke
				(width 0.1)
				(type default)
			)
			(layer "F.Fab")
		)
		(fp_line
			(start 0.12065 -0.2794)
			(end 0.12065 -0.3048)
			(stroke
				(width 0.1)
				(type default)
			)
			(layer "F.Fab")
		)
		(fp_line
			(start 0.67945 -0.3048)
			(end 0.67945 0.3048)
			(stroke
				(width 0.1)
				(type default)
			)
			(layer "F.Fab")
		)
		(fp_line
			(start 0.67945 0.3048)
			(end 0.120396 0.3048)
			(stroke
				(width 0.1)
				(type default)
			)
			(layer "F.Fab")
		)
		(pad "1" smd circle
			(at -0.40005 0)
			(size 0 0)
			(layers "F.Cu" "F.Mask" "F.Paste")
			(net "PVDDIO_P1")
		)
		(pad "2" smd circle
			(at 0.40005 0)
			(size 0 0)
			(layers "F.Cu" "F.Mask" "F.Paste")
			(net "GND")
		)
	)
)
